(kicad_pcb
	(version 20260206)
	(generator "pcbnew")
	(generator_version "10.0")
	(general
		(thickness 1.6)
		(legacy_teardrops no)
	)
	(paper "A4")
	(title_block
		(title "pdpb — Lightning_PDPB_BRD.brd")
		(comment 1 "Lightning (Wiwynn / Facebook NVMe JBOF) / footprints 1096-1096 of 1140")
	)
	(layers
		(0 "F.Cu" signal "TOP")
		(4 "In1.Cu" signal "L2GND")
		(6 "In2.Cu" signal "L3")
		(8 "In3.Cu" signal "L4VCC")
		(10 "In4.Cu" signal "L5VCC")
		(12 "In5.Cu" signal "L6")
		(14 "In6.Cu" signal "L7GND")
		(2 "B.Cu" signal "BOTTOM")
		(9 "F.Adhes" user "F.Adhesive")
		(11 "B.Adhes" user "B.Adhesive")
		(13 "F.Paste" user "Package Geometry/Pastemask Top")
		(15 "B.Paste" user "Package Geometry/Pastemask Bottom")
		(5 "F.SilkS" user "Ref Des/Silkscreen Top")
		(7 "B.SilkS" user "Ref Des/Silkscreen Bottom")
		(1 "F.Mask" user "Board Geometry/Soldermask Top")
		(3 "B.Mask" user "Board Geometry/Soldermask Bottom")
		(17 "Dwgs.User" user "User.Drawings")
		(19 "Cmts.User" user "User.Comments")
		(21 "Eco1.User" user "User.Eco1")
		(23 "Eco2.User" user "User.Eco2")
		(25 "Edge.Cuts" user "Board Geometry/Outline")
		(27 "Margin" user)
		(31 "F.CrtYd" user "Package Geometry/Place Bound Top")
		(29 "B.CrtYd" user "Package Geometry/Place Bound Bottom")
		(35 "F.Fab" user "Ref Des/Assembly Top")
		(33 "B.Fab" user "Ref Des/Assembly Bottom")
	)
	(footprint ""
		(layer "F.Cu")
		(at 41.150032 -67.669918 90)
		(property "Reference" "J9"
			(at 0 0 90)
			(layer "F.SilkS")
			(hide yes)
			(effects
				(font
					(size 1.27 1.27)
				)
			)
		)
		(property "Value" "PCISLT68-14-GP-U1"
			(at -22.225 12.7508 90)
			(unlocked yes)
			(layer "F.Fab")
			(hide yes)
			(effects
				(font
					(size 1.016 1.016)
					(thickness 0.1524)
				)
			)
		)
		(property "Device Type" "SD-78827-0001"
			(at -22.225 11.2268 90)
			(unlocked yes)
			(layer "F.Fab")
			(hide yes)
			(effects
				(font
					(size 1.016 1.016)
					(thickness 0.1524)
				)
			)
		)
		(duplicate_pad_numbers_are_jumpers no)
		(fp_line
			(start 20.4724 -3.4036)
			(end 20.4724 0.0254)
			(stroke
				(width 0.1524)
				(type default)
			)
			(layer "F.SilkS")
		)
		(fp_line
			(start -20.4724 -3.4036)
			(end 20.4724 -3.4036)
			(stroke
				(width 0.1524)
				(type default)
			)
			(layer "F.SilkS")
		)
		(fp_line
			(start 23.749 0.0254)
			(end 23.749 4.6736)
			(stroke
				(width 0.1524)
				(type default)
			)
			(layer "F.SilkS")
		)
		(fp_line
			(start 20.4724 0.0254)
			(end 23.749 0.0254)
			(stroke
				(width 0.1524)
				(type default)
			)
			(layer "F.SilkS")
		)
		(fp_line
			(start -20.4724 0.0254)
			(end -20.4724 -3.4036)
			(stroke
				(width 0.1524)
				(type default)
			)
			(layer "F.SilkS")
		)
		(fp_line
			(start -23.749 0.0254)
			(end -20.4724 0.0254)
			(stroke
				(width 0.1524)
				(type default)
			)
			(layer "F.SilkS")
		)
		(fp_line
			(start 23.117556 1.803908)
			(end 23.117556 2.896108)
			(stroke
				(width 0.3048)
				(type default)
			)
			(layer "F.SilkS")
		)
		(fp_line
			(start -20.882356 1.803908)
			(end -20.882356 2.896108)
			(stroke
				(width 0.3048)
				(type default)
			)
			(layer "F.SilkS")
		)
		(fp_line
			(start 20.882356 2.896108)
			(end 20.882356 1.803908)
			(stroke
				(width 0.3048)
				(type default)
			)
			(layer "F.SilkS")
		)
		(fp_line
			(start -23.117556 2.896108)
			(end -23.117556 1.803908)
			(stroke
				(width 0.3048)
				(type default)
			)
			(layer "F.SilkS")
		)
		(fp_line
			(start 23.749 4.6736)
			(end 20.4724 4.6736)
			(stroke
				(width 0.1524)
				(type default)
			)
			(layer "F.SilkS")
		)
		(fp_line
			(start 20.4724 4.6736)
			(end 20.4724 12.0142)
			(stroke
				(width 0.1524)
				(type default)
			)
			(layer "F.SilkS")
		)
		(fp_line
			(start -20.4724 4.6736)
			(end -23.749 4.6736)
			(stroke
				(width 0.1524)
				(type default)
			)
			(layer "F.SilkS")
		)
		(fp_line
			(start -23.749 4.6736)
			(end -23.749 0.0254)
			(stroke
				(width 0.1524)
				(type default)
			)
			(layer "F.SilkS")
		)
		(fp_line
			(start 17.8435 10.3124)
			(end -17.8435 10.3124)
			(stroke
				(width 0.1524)
				(type default)
			)
			(layer "F.SilkS")
		)
		(fp_line
			(start -17.8435 10.3124)
			(end -17.8435 12.0142)
			(stroke
				(width 0.1524)
				(type default)
			)
			(layer "F.SilkS")
		)
		(fp_line
			(start 20.4724 12.0142)
			(end 17.8435 12.0142)
			(stroke
				(width 0.1524)
				(type default)
			)
			(layer "F.SilkS")
		)
		(fp_line
			(start 17.8435 12.0142)
			(end 17.8435 10.3124)
			(stroke
				(width 0.1524)
				(type default)
			)
			(layer "F.SilkS")
		)
		(fp_line
			(start -17.8435 12.0142)
			(end -20.4724 12.0142)
			(stroke
				(width 0.1524)
				(type default)
			)
			(layer "F.SilkS")
		)
		(fp_line
			(start -20.4724 12.0142)
			(end -20.4724 4.6736)
			(stroke
				(width 0.1524)
				(type default)
			)
			(layer "F.SilkS")
		)
		(fp_arc
			(start 20.882356 1.803908)
			(mid 21.999956 0.686308)
			(end 23.117556 1.803908)
			(stroke
				(width 0.3048)
				(type default)
			)
			(layer "F.SilkS")
		)
		(fp_arc
			(start -23.117556 1.803908)
			(mid -21.999956 0.686308)
			(end -20.882356 1.803908)
			(stroke
				(width 0.3048)
				(type default)
			)
			(layer "F.SilkS")
		)
		(fp_arc
			(start 23.117556 2.896108)
			(mid 21.999956 4.013708)
			(end 20.882356 2.896108)
			(stroke
				(width 0.3048)
				(type default)
			)
			(layer "F.SilkS")
		)
		(fp_arc
			(start -20.882356 2.896108)
			(mid -21.999956 4.013708)
			(end -23.117556 2.896108)
			(stroke
				(width 0.3048)
				(type default)
			)
			(layer "F.SilkS")
		)
		(fp_poly
			(pts
				(xy -20.2184 11.7602) (xy -20.2184 4.4196) (xy -23.495 4.4196) (xy -23.495 0.2794) (xy -20.2184 0.2794)
				(xy -20.2184 -3.1496) (xy 20.2184 -3.1496) (xy 20.2184 0.2794) (xy 23.495 0.2794) (xy 23.495 4.4196)
				(xy 20.2184 4.4196) (xy 20.2184 11.7602) (xy 18.0975 11.7602) (xy 18.0975 10.0584) (xy -18.0975 10.0584)
				(xy -18.0975 11.7602)
			)
			(stroke
				(width 0)
				(type default)
			)
			(fill no)
			(layer "F.CrtYd")
		)
		(fp_poly
			(pts
				(xy -21.2471 16.256) (xy -21.2471 4.9276) (xy -24.003 4.9276) (xy -24.003 -0.2286) (xy -20.7264 -0.2286)
				(xy -20.7264 -3.6576) (xy 20.7264 -3.6576) (xy 20.7264 -0.2286) (xy 24.003 -0.2286) (xy 24.003 -0.00635)
				(xy 20.2184 -0.00635) (xy 20.2184 -3.1496) (xy -20.2184 -3.1496) (xy -20.2184 0.2794) (xy -23.495 0.2794)
				(xy -23.495 4.4196) (xy -20.2184 4.4196) (xy -20.2184 11.7602) (xy -18.0975 11.7602) (xy -18.0975 10.0584)
				(xy 18.0975 10.0584) (xy 18.0975 11.7602) (xy 20.2184 11.7602) (xy 20.2184 4.4196) (xy 23.495 4.4196)
				(xy 23.495 0.2794) (xy 20.2184 0.2794) (xy 20.2184 0.00635) (xy 24.003 0.00635) (xy 24.003 4.9276)
				(xy 21.2471 4.9276) (xy 21.2471 16.256)
			)
			(stroke
				(width 0)
				(type default)
			)
			(fill no)
			(layer "F.CrtYd")
		)
		(fp_poly
			(pts
				(xy -21.2471 16.256) (xy -21.2471 4.9276) (xy -24.003 4.9276) (xy -24.003 -0.2286) (xy -20.7264 -0.2286)
				(xy -20.7264 -3.6576) (xy 20.7264 -3.6576) (xy 20.7264 -0.2286) (xy 24.003 -0.2286) (xy 24.003 4.9276)
				(xy 21.2471 4.9276) (xy 21.2471 16.256)
			)
			(stroke
				(width 0)
				(type default)
			)
			(fill no)
			(layer "F.Fab")
		)
		(pad "" np_thru_hole circle
			(at -18.999962 0 90)
			(size 0.254 0.254)
			(drill 1.8542)
			(layers "*.Cu" "*.Mask")
			(clearance 1.1557)
			(thermal_gap 1.1557)
		)
		(pad "" np_thru_hole circle
			(at 18.999962 0 90)
			(size 0.254 0.254)
			(drill 1.8542)
			(layers "*.Cu" "*.Mask")
			(clearance 1.1557)
			(thermal_gap 1.1557)
		)
		(pad "E1" smd rect
			(at -7.079996 1.240028 90)
			(size 0.508 2.0066)
			(layers "F.Cu" "F.Mask" "F.Paste")
			(net "PE_CLK100M_DR9_2_P")
		)
		(pad "E2" smd rect
			(at -6.279896 1.240028 90)
			(size 0.508 2.0066)
			(layers "F.Cu" "F.Mask" "F.Paste")
			(net "PE_CLK100M_DR9_2_N")
		)
		(pad "E3" smd rect
			(at -5.48005 1.240028 90)
			(size 0.508 2.0066)
			(layers "F.Cu" "F.Mask" "F.Paste")
			(net "P3V3")
		)
		(pad "E4" smd rect
			(at -4.67995 1.240028 90)
			(size 0.508 2.0066)
			(layers "F.Cu" "F.Mask" "F.Paste")
			(net "SSD9_PERST_N")
		)
		(pad "E5" smd rect
			(at -3.880104 1.240028 90)
			(size 0.508 2.0066)
			(layers "F.Cu" "F.Mask" "F.Paste")
			(net "SSD9_PERST_N")
		)
		(pad "E6" smd rect
			(at -3.080004 1.240028 90)
			(size 0.508 2.0066)
			(layers "F.Cu" "F.Mask" "F.Paste")
			(net "Net_1071")
		)
		(pad "E7" smd rect
			(at -15.48003 -1.949958 90)
			(size 0.508 2.0066)
			(layers "F.Cu" "F.Mask" "F.Paste")
			(net "PE_CLK100M_DR9_1_P")
		)
		(pad "E8" smd rect
			(at -14.67993 -1.949958 90)
			(size 0.508 2.0066)
			(layers "F.Cu" "F.Mask" "F.Paste")
			(net "PE_CLK100M_DR9_1_N")
		)
		(pad "E9" smd rect
			(at -13.880084 -1.949958 90)
			(size 0.508 2.0066)
			(layers "F.Cu" "F.Mask" "F.Paste")
			(net "GND")
		)
		(pad "E10" smd rect
			(at -13.079984 -1.949958 90)
			(size 0.508 2.0066)
			(layers "F.Cu" "F.Mask" "F.Paste")
			(net "PE_TX1_DR9_N")
		)
		(pad "E11" smd rect
			(at -12.279884 -1.949958 90)
			(size 0.508 2.0066)
			(layers "F.Cu" "F.Mask" "F.Paste")
			(net "PE_TX1_DR9_P")
		)
		(pad "E12" smd rect
			(at -11.480038 -1.949958 90)
			(size 0.508 2.0066)
			(layers "F.Cu" "F.Mask" "F.Paste")
			(net "GND")
		)
		(pad "E13" smd rect
			(at -10.679938 -1.949958 90)
			(size 0.508 2.0066)
			(layers "F.Cu" "F.Mask" "F.Paste")
			(net "PE_RX1_DR9_N")
		)
		(pad "E14" smd rect
			(at -9.880092 -1.949958 90)
			(size 0.508 2.0066)
			(layers "F.Cu" "F.Mask" "F.Paste")
			(net "PE_RX1_DR9_P")
		)
		(pad "E15" smd rect
			(at -9.079992 -1.949958 90)
			(size 0.508 2.0066)
			(layers "F.Cu" "F.Mask" "F.Paste")
			(net "GND")
		)
		(pad "E16" smd rect
			(at -8.279892 -1.949958 90)
			(size 0.508 2.0066)
			(layers "F.Cu" "F.Mask" "F.Paste")
			(net "Net_1078")
		)
		(pad "E17" smd rect
			(at 9.320022 -1.949958 90)
			(size 0.508 2.0066)
			(layers "F.Cu" "F.Mask" "F.Paste")
			(net "PE_TX4_DR9_N")
		)
		(pad "E18" smd rect
			(at 10.120122 -1.949958 90)
			(size 0.508 2.0066)
			(layers "F.Cu" "F.Mask" "F.Paste")
			(net "PE_TX4_DR9_P")
		)
		(pad "E19" smd rect
			(at 10.919968 -1.949958 90)
			(size 0.508 2.0066)
			(layers "F.Cu" "F.Mask" "F.Paste")
			(net "GND")
		)
		(pad "E20" smd rect
			(at 11.720068 -1.949958 90)
			(size 0.508 2.0066)
			(layers "F.Cu" "F.Mask" "F.Paste")
			(net "PE_RX4_DR9_N")
		)
		(pad "E21" smd rect
			(at 12.519914 -1.949958 90)
			(size 0.508 2.0066)
			(layers "F.Cu" "F.Mask" "F.Paste")
			(net "PE_RX4_DR9_P")
		)
		(pad "E22" smd rect
			(at 13.320014 -1.949958 90)
			(size 0.508 2.0066)
			(layers "F.Cu" "F.Mask" "F.Paste")
			(net "GND")
		)
		(pad "E23" smd rect
			(at 14.120114 -1.949958 90)
			(size 0.508 2.0066)
			(layers "F.Cu" "F.Mask" "F.Paste")
			(net "SCL_DR9_R")
		)
		(pad "E24" smd rect
			(at 14.91996 -1.949958 90)
			(size 0.508 2.0066)
			(layers "F.Cu" "F.Mask" "F.Paste")
			(net "SDA_DR9_R")
		)
		(pad "E25" smd rect
			(at 15.72006 -1.949958 90)
			(size 0.508 2.0066)
			(layers "F.Cu" "F.Mask" "F.Paste")
			(net "DUALPORTEN#9")
		)
		(pad "P1" smd rect
			(at -1.905 0.824992 90)
			(size 0.6604 2.0574)
			(layers "F.Cu" "F.Mask" "F.Paste")
			(net "Net_1074")
		)
		(pad "P2" smd rect
			(at -0.635 0.824992 90)
			(size 0.6604 2.0574)
			(layers "F.Cu" "F.Mask" "F.Paste")
			(net "Net_1073")
		)
		(pad "P3" smd rect
			(at 0.635 0.824992 90)
			(size 0.6604 2.0574)
			(layers "F.Cu" "F.Mask" "F.Paste")
			(net "Net_1072")
		)
		(pad "P4" smd rect
			(at 1.905 0.824992 90)
			(size 0.6604 2.0574)
			(layers "F.Cu" "F.Mask" "F.Paste")
			(net "SSD9_CLK0_OE_N")
		)
		(pad "P5" smd rect
			(at 3.175 0.824992 90)
			(size 0.6604 2.0574)
			(layers "F.Cu" "F.Mask" "F.Paste")
			(net "GND")
		)
		(pad "P6" smd rect
			(at 4.445 0.824992 90)
			(size 0.6604 2.0574)
			(layers "F.Cu" "F.Mask" "F.Paste")
			(net "GND")
		)
		(pad "P7" smd rect
			(at 5.715 0.824992 90)
			(size 0.6604 2.0574)
			(layers "F.Cu" "F.Mask" "F.Paste")
			(net "Net_96")
		)
		(pad "P8" smd rect
			(at 6.985 0.824992 90)
			(size 0.6604 2.0574)
			(layers "F.Cu" "F.Mask" "F.Paste")
			(net "Net_68")
		)
		(pad "P9" smd rect
			(at 8.255 0.824992 90)
			(size 0.6604 2.0574)
			(layers "F.Cu" "F.Mask" "F.Paste")
			(net "Net_82")
		)
		(pad "P10" smd rect
			(at 9.525 0.824992 90)
			(size 0.6604 2.0574)
			(layers "F.Cu" "F.Mask" "F.Paste")
			(net "SSD_PRSNT_NET9")
		)
		(pad "P11" smd rect
			(at 10.795 0.824992 90)
			(size 0.6604 2.0574)
			(layers "F.Cu" "F.Mask" "F.Paste")
			(net "SSD_ACT_DR9")
		)
		(pad "P12" smd rect
			(at 12.065 0.824992 90)
			(size 0.6604 2.0574)
			(layers "F.Cu" "F.Mask" "F.Paste")
			(net "GND")
		)
		(pad "P13" smd rect
			(at 13.335 0.824992 90)
			(size 0.6604 2.0574)
			(layers "F.Cu" "F.Mask" "F.Paste")
			(net "12V_PRECH_SSD9")
		)
		(pad "P14" smd rect
			(at 14.605 0.824992 90)
			(size 0.6604 2.0574)
			(layers "F.Cu" "F.Mask" "F.Paste")
			(net "P12V_SSD9")
		)
		(pad "P15" smd rect
			(at 15.875 0.824992 90)
			(size 0.6604 2.0574)
			(layers "F.Cu" "F.Mask" "F.Paste")
			(net "P12V_SSD9")
		)
		(pad "PTH1" thru_hole oval
			(at -21.999956 2.350008 90)
			(size 1.524 2.6162)
			(drill oval 0.8128 1.905)
			(layers "*.Cu" "*.Mask")
			(remove_unused_layers no)
			(net "Net_1083")
			(clearance 0.1524)
			(thermal_gap 0.1524)
		)
		(pad "PTH2" thru_hole oval
			(at 21.999956 2.350008 90)
			(size 1.524 2.6162)
			(drill oval 0.8128 1.905)
			(layers "*.Cu" "*.Mask")
			(remove_unused_layers no)
			(net "Net_1067")
			(clearance 0.1524)
			(thermal_gap 0.1524)
		)
		(pad "S1" smd rect
			(at -15.875 0.824992 90)
			(size 0.6604 2.0574)
			(layers "F.Cu" "F.Mask" "F.Paste")
			(net "GND")
		)
		(pad "S2" smd rect
			(at -14.605 0.824992 90)
			(size 0.6604 2.0574)
			(layers "F.Cu" "F.Mask" "F.Paste")
			(net "Net_1082")
		)
		(pad "S3" smd rect
			(at -13.335 0.824992 90)
			(size 0.6604 2.0574)
			(layers "F.Cu" "F.Mask" "F.Paste")
			(net "Net_1081")
		)
		(pad "S4" smd rect
			(at -12.065 0.824992 90)
			(size 0.6604 2.0574)
			(layers "F.Cu" "F.Mask" "F.Paste")
			(net "GND")
		)
		(pad "S5" smd rect
			(at -10.795 0.824992 90)
			(size 0.6604 2.0574)
			(layers "F.Cu" "F.Mask" "F.Paste")
			(net "Net_1080")
		)
		(pad "S6" smd rect
			(at -9.525 0.824992 90)
			(size 0.6604 2.0574)
			(layers "F.Cu" "F.Mask" "F.Paste")
			(net "Net_1079")
		)
		(pad "S7" smd rect
			(at -8.255 0.824992 90)
			(size 0.6604 2.0574)
			(layers "F.Cu" "F.Mask" "F.Paste")
			(net "GND")
		)
		(pad "S8" smd rect
			(at -7.480046 -1.949958 90)
			(size 0.508 2.0066)
			(layers "F.Cu" "F.Mask" "F.Paste")
			(net "GND")
		)
		(pad "S9" smd rect
			(at -6.679946 -1.949958 90)
			(size 0.508 2.0066)
			(layers "F.Cu" "F.Mask" "F.Paste")
			(net "Net_1077")
		)
		(pad "S10" smd rect
			(at -5.8801 -1.949958 90)
			(size 0.508 2.0066)
			(layers "F.Cu" "F.Mask" "F.Paste")
			(net "Net_1076")
		)
		(pad "S11" smd rect
			(at -5.08 -1.949958 90)
			(size 0.508 2.0066)
			(layers "F.Cu" "F.Mask" "F.Paste")
			(net "GND")
		)
		(pad "S12" smd rect
			(at -4.2799 -1.949958 90)
			(size 0.508 2.0066)
			(layers "F.Cu" "F.Mask" "F.Paste")
			(net "Net_1075")
		)
		(pad "S13" smd rect
			(at -3.480054 -1.949958 90)
			(size 0.508 2.0066)
			(layers "F.Cu" "F.Mask" "F.Paste")
			(net "Net_1070")
		)
		(pad "S14" smd rect
			(at -2.679954 -1.949958 90)
			(size 0.508 2.0066)
			(layers "F.Cu" "F.Mask" "F.Paste")
			(net "GND")
		)
		(pad "S15" smd rect
			(at -1.880108 -1.949958 90)
			(size 0.508 2.0066)
			(layers "F.Cu" "F.Mask" "F.Paste")
			(net "Net_1069")
		)
		(pad "S16" smd rect
			(at -1.080008 -1.949958 90)
			(size 0.508 2.0066)
			(layers "F.Cu" "F.Mask" "F.Paste")
			(net "GND")
		)
		(pad "S17" smd rect
			(at -0.279908 -1.949958 90)
			(size 0.508 2.0066)
			(layers "F.Cu" "F.Mask" "F.Paste")
			(net "PE_TX2_DR9_N")
		)
		(pad "S18" smd rect
			(at 0.519938 -1.949958 90)
			(size 0.508 2.0066)
			(layers "F.Cu" "F.Mask" "F.Paste")
			(net "PE_TX2_DR9_P")
		)
		(pad "S19" smd rect
			(at 1.320038 -1.949958 90)
			(size 0.508 2.0066)
			(layers "F.Cu" "F.Mask" "F.Paste")
			(net "GND")
		)
		(pad "S20" smd rect
			(at 2.119884 -1.949958 90)
			(size 0.508 2.0066)
			(layers "F.Cu" "F.Mask" "F.Paste")
			(net "PE_RX2_DR9_N")
		)
		(pad "S21" smd rect
			(at 2.919984 -1.949958 90)
			(size 0.508 2.0066)
			(layers "F.Cu" "F.Mask" "F.Paste")
			(net "PE_RX2_DR9_P")
		)
		(pad "S22" smd rect
			(at 3.720084 -1.949958 90)
			(size 0.508 2.0066)
			(layers "F.Cu" "F.Mask" "F.Paste")
			(net "GND")
		)
		(pad "S23" smd rect
			(at 4.51993 -1.949958 90)
			(size 0.508 2.0066)
			(layers "F.Cu" "F.Mask" "F.Paste")
			(net "PE_TX3_DR9_N")
		)
		(pad "S24" smd rect
			(at 5.32003 -1.949958 90)
			(size 0.508 2.0066)
			(layers "F.Cu" "F.Mask" "F.Paste")
			(net "PE_TX3_DR9_P")
		)
		(pad "S25" smd rect
			(at 6.119876 -1.949958 90)
			(size 0.508 2.0066)
			(layers "F.Cu" "F.Mask" "F.Paste")
			(net "GND")
		)
		(pad "S26" smd rect
			(at 6.919976 -1.949958 90)
			(size 0.508 2.0066)
			(layers "F.Cu" "F.Mask" "F.Paste")
			(net "PE_RX3_DR9_N")
		)
		(pad "S27" smd rect
			(at 7.720076 -1.949958 90)
			(size 0.508 2.0066)
			(layers "F.Cu" "F.Mask" "F.Paste")
			(net "PE_RX3_DR9_P")
		)
		(pad "S28" smd rect
			(at 8.519922 -1.949958 90)
			(size 0.508 2.0066)
			(layers "F.Cu" "F.Mask" "F.Paste")
			(net "GND")
		)
		(zone
			(layers "F.Cu" "B.Cu" "In1.Cu" "In2.Cu" "In3.Cu" "In4.Cu" "In5.Cu" "In6.Cu")
			(hatch none 0.5)
			(connect_pads
				(clearance 0)
			)
			(min_thickness 0.25)
			(keepout
				(tracks not_allowed)
				(vias allowed)
				(pads allowed)
				(copperpour not_allowed)
				(footprints allowed)
			)
			(placement
				(enabled no)
				(sheetname "")
			)
			(fill
				(thermal_gap 0.5)
				(thermal_bridge_width 0.5)
				(island_removal_mode 0)
			)
			(polygon
				(pts
					(arc
						(start 42.381932 -86.66988)
						(mid 39.918132 -86.66988)
						(end 42.381932 -86.66988)
					)
				)
			)
		)
		(zone
			(layers "F.Cu" "B.Cu" "In1.Cu" "In2.Cu" "In3.Cu" "In4.Cu" "In5.Cu" "In6.Cu")
			(hatch none 0.5)
			(connect_pads
				(clearance 0)
			)
			(min_thickness 0.25)
			(keepout
				(tracks not_allowed)
				(vias allowed)
				(pads allowed)
				(copperpour not_allowed)
				(footprints allowed)
			)
			(placement
				(enabled no)
				(sheetname "")
			)
			(fill
				(thermal_gap 0.5)
				(thermal_bridge_width 0.5)
				(island_removal_mode 0)
			)
			(polygon
				(pts
					(arc
						(start 42.381932 -48.669956)
						(mid 39.918132 -48.669956)
						(end 42.381932 -48.669956)
					)
				)
			)
		)
	)
)
